FILE_TYPE = MACRO_DRAWING;
SET COLOR_WIRE YELLOW;
SET COLOR_PROP ORANGE;
SET COLOR_DOT WHITE;
SET COLOR_ARC YELLOW;
SET COLOR_BODY GREEN;
SET COLOR_NOTE PURPLE;
SET PROP_DISPLAY VALUE;
SET PAGE_NUMBER P196;
FORCEADD QUANTA_TITLE_BLOCK_C..1
(0 0);
FORCEPROP 1 LAST CUSTOM_TXT_CDS <NAME_2>
J 0
(-3175 50);
FORCEPROP 1 LAST CUSTOM_TXT_CDS <NAME_1>
J 0
(-3175 175);
FORCEPROP 1 LAST CUSTOM_TXT_CDS <Q_NUMBER>
J 0
(-1403 103);
DISPLAY 1.212766 (-1403 103);
FORCEPROP 1 LAST CUSTOM_TXT_CDS <Q_PROJ>
J 0
(-2382 102);
DISPLAY 1.212766 (-2382 102);
FORCEPROP 1 LAST CUSTOM_TXT_CDS <Q_REV>
J 0
(-184 103);
DISPLAY 1.212766 (-184 103);
FORCEPROP 1 LAST CUSTOM_TXT_CDS <CON_LAST_MODIFIED>
J 0
(-1885 15);
DISPLAY 0.978723 (-1885 15);
FORCEPROP 1 LAST CUSTOM_TXT_CDS <CON_PAGE_NUM> OF <CON_TOTAL_PAGES>
J 0
(-446 18);
DISPLAY 0.978723 (-446 18);
FORCEPROP 1 LAST Q_DEPT BU9
J 1
(-3763 49);
DISPLAY 1.957447 (-3763 49);
PAINT GREEN (-3763 49);
FORCEPROP 1 LAST Q_TITLE Blank
J 0
(-9366 26);
DISPLAY 2.446809 (-9366 26);
PAINT GREEN (-9366 26);
FORCEPROP 0 LAST CDS_CON_LAST_MODIFIED Wed Jul 21 11:38:12 2021
J 0
(-1885 15);
DISPLAY INVISIBLE (-1885 15);
FORCEPROP 1 LAST CDS_LMAN_SYM_OUTLINE -9475,6775,100,-125
J 0
(0 0);
DISPLAY 0.468085 (0 0);
PAINT GREEN (0 0);
DISPLAY INVISIBLE (0 0);
FORCEPROP 2 LAST CDS_LIB pure_quanta
J 0
(0 0);
DISPLAY INVISIBLE (0 0);
FORCEPROP 2 LAST PAGE_BORDER TRUE
J 0
(-7890 5250);
DISPLAY 0.638298 (-7890 5250);
PAINT PINK (-7890 5250);
DISPLAY INVISIBLE (-7890 5250);
FORCEPROP 1 LAST COMMENT_BODY TRUE
J 0
(12 -13);
DISPLAY 0.978723 (12 -13);
PAINT GREEN (12 -13);
DISPLAY INVISIBLE (12 -13);
FORCEPROP 2 LAST CUSTOM_TXT_CDS <XR_PAGE_TITLE>
J 0
(-7890 5250);
DISPLAY 0.638298 (-7890 5250);
PAINT PINK (-7890 5250);
DISPLAY INVISIBLE (-7890 5250);
FORCEPROP 2 LAST CDS_XR_PAGE_TITLE CR-197 : @T6G_MB_LIB.T6G(SCH_1):PAGE197
J 0
(-7890 5250);
DISPLAY 0.638298 (-7890 5250);
PAINT PINK (-7890 5250);
DISPLAY INVISIBLE (-7890 5250);
QUIT
